%FSTAX23Y23*%
%MOIN*%
%SFA1B1*%

%IPPOS*%
%ADD13C,0.010000*%
%ADD17C,0.006000*%
%LNgrandmaster-1*%
%LPD*%
G54D13*
X0021Y0283D02*
D01*
X0021Y02834*
X00209Y02838*
X00209Y02842*
X00208Y02846*
X00206Y0285*
X00205Y02854*
X00203Y02858*
X00201Y02862*
X00198Y02865*
X00196Y02869*
X00193Y02872*
X0019Y02875*
X00187Y02878*
X00183Y0288*
X0018Y02882*
X00176Y02884*
X00172Y02886*
X00168Y02888*
X00164Y02889*
X0016Y0289*
X00155Y0289*
X00151Y02891*
X00147*
X00143Y0289*
X00138Y0289*
X00134Y02889*
X0013Y02888*
X00126Y02886*
X00122Y02884*
X00118Y02882*
X00115Y0288*
X00111Y02878*
X00108Y02875*
X00105Y02872*
X00102Y02869*
X001Y02865*
X00097Y02862*
X00095Y02858*
X00093Y02854*
X00092Y0285*
X0009Y02846*
X00089Y02842*
X00089Y02838*
X00088Y02834*
X00088Y0283*
X00088Y02825*
X00089Y02821*
X00089Y02817*
X0009Y02813*
X00092Y02809*
X00093Y02805*
X00095Y02801*
X00097Y02797*
X001Y02794*
X00102Y0279*
X00105Y02787*
X00108Y02784*
X00111Y02781*
X00115Y02779*
X00119Y02777*
X00122Y02775*
X00126Y02773*
X0013Y02772*
X00134Y0277*
X00138Y02769*
X00143Y02769*
X00147Y02769*
X00151*
X00155Y02769*
X0016Y02769*
X00164Y0277*
X00168Y02772*
X00172Y02773*
X00176Y02775*
X0018Y02777*
X00183Y02779*
X00187Y02781*
X0019Y02784*
X00193Y02787*
X00196Y0279*
X00198Y02794*
X00201Y02797*
X00203Y02801*
X00205Y02805*
X00206Y02809*
X00208Y02813*
X00209Y02817*
X00209Y02821*
X0021Y02825*
X0021Y0283*
X02592D02*
D01*
X02592Y02834*
X02591Y02838*
X02591Y02842*
X0259Y02846*
X02588Y0285*
X02587Y02854*
X02585Y02858*
X02583Y02862*
X0258Y02865*
X02578Y02869*
X02575Y02872*
X02572Y02875*
X02568Y02878*
X02565Y0288*
X02561Y02882*
X02558Y02884*
X02554Y02886*
X0255Y02888*
X02546Y02889*
X02541Y0289*
X02537Y0289*
X02533Y02891*
X02529*
X02525Y0289*
X0252Y0289*
X02516Y02889*
X02512Y02888*
X02508Y02886*
X02504Y02884*
X025Y02882*
X02497Y0288*
X02493Y02878*
X0249Y02875*
X02487Y02872*
X02484Y02869*
X02482Y02865*
X02479Y02862*
X02477Y02858*
X02475Y02854*
X02474Y0285*
X02472Y02846*
X02471Y02842*
X0247Y02838*
X0247Y02834*
X0247Y0283*
X0247Y02825*
X0247Y02821*
X02471Y02817*
X02472Y02813*
X02474Y02809*
X02475Y02805*
X02477Y02801*
X02479Y02797*
X02482Y02794*
X02484Y0279*
X02487Y02787*
X0249Y02784*
X02493Y02781*
X02497Y02779*
X025Y02777*
X02504Y02775*
X02508Y02773*
X02512Y02772*
X02516Y0277*
X0252Y02769*
X02525Y02769*
X02529Y02769*
X02533*
X02537Y02769*
X02541Y02769*
X02546Y0277*
X0255Y02772*
X02554Y02773*
X02558Y02775*
X02561Y02777*
X02565Y02779*
X02568Y02781*
X02572Y02784*
X02575Y02787*
X02578Y0279*
X0258Y02794*
X02583Y02797*
X02585Y02801*
X02587Y02805*
X02588Y02809*
X0259Y02813*
X02591Y02817*
X02591Y02821*
X02592Y02825*
X02592Y0283*
Y03853D02*
D01*
X02592Y03857*
X02591Y03862*
X02591Y03866*
X0259Y0387*
X02588Y03874*
X02587Y03878*
X02585Y03882*
X02583Y03886*
X0258Y03889*
X02578Y03892*
X02575Y03896*
X02572Y03899*
X02568Y03901*
X02565Y03904*
X02561Y03906*
X02558Y03908*
X02554Y0391*
X0255Y03911*
X02546Y03912*
X02541Y03913*
X02537Y03914*
X02533Y03914*
X02529*
X02525Y03914*
X0252Y03913*
X02516Y03912*
X02512Y03911*
X02508Y0391*
X02504Y03908*
X025Y03906*
X02497Y03904*
X02493Y03901*
X0249Y03899*
X02487Y03896*
X02484Y03892*
X02482Y03889*
X02479Y03886*
X02477Y03882*
X02475Y03878*
X02474Y03874*
X02472Y0387*
X02471Y03866*
X0247Y03862*
X0247Y03857*
X0247Y03853*
X0247Y03849*
X0247Y03845*
X02471Y0384*
X02472Y03836*
X02474Y03832*
X02475Y03828*
X02477Y03825*
X02479Y03821*
X02482Y03817*
X02484Y03814*
X02487Y03811*
X0249Y03808*
X02493Y03805*
X02497Y03803*
X025Y038*
X02504Y03798*
X02508Y03797*
X02512Y03795*
X02516Y03794*
X0252Y03793*
X02525Y03792*
X02529Y03792*
X02533*
X02537Y03792*
X02541Y03793*
X02546Y03794*
X0255Y03795*
X02554Y03797*
X02558Y03798*
X02561Y038*
X02565Y03803*
X02568Y03805*
X02572Y03808*
X02575Y03811*
X02578Y03814*
X0258Y03817*
X02583Y03821*
X02585Y03825*
X02587Y03828*
X02588Y03832*
X0259Y03836*
X02591Y0384*
X02591Y03845*
X02592Y03849*
X02592Y03853*
X00018Y03966D02*
X02662D01*
X00018Y02716D02*
Y03966D01*
Y02716D02*
X02662D01*
Y03966*
X02657Y04032D02*
Y04007D01*
X02652Y04002*
X02642*
X02637Y04007*
Y04032*
X02627Y04002D02*
X02617D01*
X02622*
Y04032*
X02627Y04027*
X02587Y04002D02*
Y04032D01*
X02602Y04017*
X02582*
X02331Y00479D02*
X02336Y00474D01*
Y00464*
X02331Y00459*
X02311*
X02306Y00464*
Y00474*
X02311Y00479*
X02306Y00504D02*
X02336D01*
X02321Y00489*
Y00509*
X02306Y00534D02*
X02336D01*
X02321Y00519*
Y00539*
X024Y00477D02*
X02405Y00472D01*
Y00462*
X024Y00457*
X0238*
X02375Y00462*
Y00472*
X0238Y00477*
X02375Y00502D02*
X02405D01*
X0239Y00487*
Y00507*
X02405Y00537D02*
Y00517D01*
X0239*
X02395Y00527*
Y00532*
X0239Y00537*
X0238*
X02375Y00532*
Y00522*
X0238Y00517*
X02475Y00461D02*
X0248Y00456D01*
Y00446*
X02475Y00441*
X02455*
X0245Y00446*
Y00456*
X02455Y00461*
X0245Y00486D02*
X0248D01*
X02465Y00471*
Y00491*
X0248Y00521D02*
X02475Y00511D01*
X02465Y00501*
X02455*
X0245Y00506*
Y00516*
X02455Y00521*
X0246*
X02465Y00516*
Y00501*
X02544Y00461D02*
X02549Y00456D01*
Y00446*
X02544Y00441*
X02524*
X02519Y00446*
Y00456*
X02524Y00461*
X02519Y00486D02*
X02549D01*
X02534Y00471*
Y00491*
X02549Y00501D02*
Y00521D01*
X02544*
X02524Y00501*
X02519*
X02659Y00461D02*
X02664Y00456D01*
Y00446*
X02659Y00441*
X02639*
X02634Y00446*
Y00456*
X02639Y00461*
X02634Y00486D02*
X02664D01*
X02649Y00471*
Y00491*
X02659Y00501D02*
X02664Y00506D01*
Y00516*
X02659Y00521*
X02654*
X02649Y00516*
X02644Y00521*
X02639*
X02634Y00516*
Y00506*
X02639Y00501*
X02644*
X02649Y00506*
X02654Y00501*
X02659*
X02649Y00506D02*
Y00516D01*
X02727Y00461D02*
X02732Y00456D01*
Y00446*
X02727Y00441*
X02707*
X02702Y00446*
Y00456*
X02707Y00461*
X02702Y00486D02*
X02732D01*
X02717Y00471*
Y00491*
X02707Y00501D02*
X02702Y00506D01*
Y00516*
X02707Y00521*
X02727*
X02732Y00516*
Y00506*
X02727Y00501*
X02722*
X02717Y00506*
Y00521*
X02818Y00461D02*
X02823Y00456D01*
Y00446*
X02818Y00441*
X02798*
X02793Y00446*
Y00456*
X02798Y00461*
X02823Y00491D02*
Y00471D01*
X02808*
X02813Y00481*
Y00486*
X02808Y00491*
X02798*
X02793Y00486*
Y00476*
X02798Y00471*
X02818Y00501D02*
X02823Y00506D01*
Y00516*
X02818Y00521*
X02798*
X02793Y00516*
Y00506*
X02798Y00501*
X02818*
X02889Y00461D02*
X02894Y00456D01*
Y00446*
X02889Y00441*
X02869*
X02864Y00446*
Y00456*
X02869Y00461*
X02894Y00491D02*
Y00471D01*
X02879*
X02884Y00481*
Y00486*
X02879Y00491*
X02869*
X02864Y00486*
Y00476*
X02869Y00471*
X02864Y00501D02*
Y00511D01*
Y00506*
X02894*
X02889Y00501*
X02984Y00461D02*
X02989Y00456D01*
Y00446*
X02984Y00441*
X02964*
X02959Y00446*
Y00456*
X02964Y00461*
X02989Y00491D02*
Y00471D01*
X02974*
X02979Y00481*
Y00486*
X02974Y00491*
X02964*
X02959Y00486*
Y00476*
X02964Y00471*
X02959Y00521D02*
Y00501D01*
X02979Y00521*
X02984*
X02989Y00516*
Y00506*
X02984Y00501*
X0305Y00461D02*
X03055Y00456D01*
Y00446*
X0305Y00441*
X0303*
X03025Y00446*
Y00456*
X0303Y00461*
X03055Y00491D02*
Y00471D01*
X0304*
X03045Y00481*
Y00486*
X0304Y00491*
X0303*
X03025Y00486*
Y00476*
X0303Y00471*
X0305Y00501D02*
X03055Y00506D01*
Y00516*
X0305Y00521*
X03045*
X0304Y00516*
Y00511*
Y00516*
X03035Y00521*
X0303*
X03025Y00516*
Y00506*
X0303Y00501*
X02849Y03022D02*
X02854Y03027D01*
X02864*
X02869Y03022*
Y03002*
X02864Y02997*
X02854*
X02849Y03002*
X02839D02*
X02834Y02997D01*
X02824*
X02819Y03002*
Y03022*
X02824Y03027*
X02834*
X02839Y03022*
Y03017*
X02834Y03012*
X02819*
X02809Y03022D02*
X02804Y03027D01*
X02794*
X02789Y03022*
Y03002*
X02794Y02997*
X02804*
X02809Y03002*
Y03022*
X02629Y031D02*
X02634Y03095D01*
Y03085*
X02629Y0308*
X02609*
X02604Y03085*
Y03095*
X02609Y031*
X02629Y0311D02*
X02634Y03115D01*
Y03125*
X02629Y0313*
X02624*
X02619Y03125*
X02614Y0313*
X02609*
X02604Y03125*
Y03115*
X02609Y0311*
X02614*
X02619Y03115*
X02624Y0311*
X02629*
X02619Y03115D02*
Y03125D01*
X02609Y0314D02*
X02604Y03145D01*
Y03155*
X02609Y0316*
X02629*
X02634Y03155*
Y03145*
X02629Y0314*
X02624*
X02619Y03145*
Y0316*
X02299Y02848D02*
X02304Y02853D01*
X02314*
X02319Y02848*
Y02828*
X02314Y02823*
X02304*
X02299Y02828*
X02289Y02848D02*
X02284Y02853D01*
X02274*
X02269Y02848*
Y02843*
X02274Y02838*
X02269Y02833*
Y02828*
X02274Y02823*
X02284*
X02289Y02828*
Y02833*
X02284Y02838*
X02289Y02843*
Y02848*
X02284Y02838D02*
X02274D01*
X02259Y02848D02*
X02254Y02853D01*
X02244*
X02239Y02848*
Y02843*
X02244Y02838*
X02239Y02833*
Y02828*
X02244Y02823*
X02254*
X02259Y02828*
Y02833*
X02254Y02838*
X02259Y02843*
Y02848*
X02254Y02838D02*
X02244D01*
X02258Y02948D02*
X02263Y02953D01*
X02273*
X02278Y02948*
Y02928*
X02273Y02923*
X02263*
X02258Y02928*
X02248Y02948D02*
X02243Y02953D01*
X02233*
X02228Y02948*
Y02943*
X02233Y02938*
X02228Y02933*
Y02928*
X02233Y02923*
X02243*
X02248Y02928*
Y02933*
X02243Y02938*
X02248Y02943*
Y02948*
X02243Y02938D02*
X02233D01*
X02218Y02953D02*
X02198D01*
Y02948*
X02218Y02928*
Y02923*
G54D17*
X02594Y02977D02*
Y03037D01*
X0267Y02977D02*
Y03037D01*
X02332Y02906D02*
X02392D01*
X02332Y02982D02*
X02392D01*
M02*